(kicad_pcb
	(version 20260206)
	(generator "pcbnew")
	(generator_version "10.0")
	(general
		(thickness 1.6)
		(legacy_teardrops no)
	)
	(paper "A4")
	(title_block
		(title "Bryce Canyon_LED_16347-1_OCP.brd")
		(comment 1 "Bryce Canyon / footprints 15-20 of 49")
	)
	(layers
		(0 "F.Cu" signal "TOP")
		(2 "B.Cu" signal "BOTTOM")
		(9 "F.Adhes" user "F.Adhesive")
		(11 "B.Adhes" user "B.Adhesive")
		(13 "F.Paste" user "Package Geometry/Pastemask Top")
		(15 "B.Paste" user "Package Geometry/Pastemask Bottom")
		(5 "F.SilkS" user "Ref Des/Silkscreen Top")
		(7 "B.SilkS" user "Ref Des/Silkscreen Bottom")
		(1 "F.Mask" user "Board Geometry/Soldermask Top")
		(3 "B.Mask" user "Board Geometry/Soldermask Bottom")
		(17 "Dwgs.User" user "User.Drawings")
		(19 "Cmts.User" user "User.Comments")
		(21 "Eco1.User" user "User.Eco1")
		(23 "Eco2.User" user "User.Eco2")
		(25 "Edge.Cuts" user "Board Geometry/Outline")
		(27 "Margin" user)
		(31 "F.CrtYd" user "Package Geometry/Place Bound Top")
		(29 "B.CrtYd" user "Package Geometry/Place Bound Bottom")
		(35 "F.Fab" user "Ref Des/Assembly Top")
		(33 "B.Fab" user "Ref Des/Assembly Bottom")
	)
	(footprint ""
		(layer "B.Cu")
		(at 32.0294 -5.0546)
		(property "Reference" "Q4"
			(at 0 0 0)
			(layer "B.SilkS")
			(hide yes)
			(effects
				(font
					(size 1.27 1.27)
				)
				(justify mirror)
			)
		)
		(property "Value" "SSM3K324R-GP"
			(at -0.127 -8.9662 0)
			(unlocked yes)
			(layer "B.Fab")
			(hide yes)
			(effects
				(font
					(size 1.016 1.016)
					(thickness 0.1524)
				)
				(justify mirror)
			)
		)
		(property "Device Type" "SOT23DGS2D4H35"
			(at -0.127 -10.4902 0)
			(unlocked yes)
			(layer "B.Fab")
			(hide yes)
			(effects
				(font
					(size 1.016 1.016)
					(thickness 0.1524)
				)
				(justify mirror)
			)
		)
		(duplicate_pad_numbers_are_jumpers no)
		(fp_line
			(start -1.651 -1.778)
			(end 1.651 -1.778)
			(stroke
				(width 0.1524)
				(type default)
			)
			(layer "B.SilkS")
		)
		(fp_line
			(start -1.651 1.778)
			(end -1.651 -1.778)
			(stroke
				(width 0.1524)
				(type default)
			)
			(layer "B.SilkS")
		)
		(fp_line
			(start 1.651 -1.778)
			(end 1.651 1.778)
			(stroke
				(width 0.1524)
				(type default)
			)
			(layer "B.SilkS")
		)
		(fp_line
			(start 1.651 1.778)
			(end -1.651 1.778)
			(stroke
				(width 0.1524)
				(type default)
			)
			(layer "B.SilkS")
		)
		(fp_poly
			(pts
				(xy 1.778 1.8796) (xy 1.778 -1.8796) (xy -1.778 -1.8796) (xy -1.778 1.8796)
			)
			(stroke
				(width 0)
				(type default)
			)
			(fill no)
			(layer "B.CrtYd")
		)
		(fp_poly
			(pts
				(xy 1.778 1.8796) (xy 1.778 -1.8796) (xy -1.778 -1.8796) (xy -1.778 1.8796)
			)
			(stroke
				(width 0)
				(type default)
			)
			(fill no)
			(layer "B.Fab")
		)
		(pad "D" smd custom
			(at 0 -0.9525 180)
			(size 0.1905 0.1905)
			(layers "B.Cu" "B.Mask" "B.Paste")
			(net "DRV_ACT_25_31_N")
			(options
				(clearance outline)
				(anchor circle)
			)
			(primitives
				(gr_poly
					(pts
						(arc
							(start -0.1778 -0.5715)
							(mid -0.321484 -0.511984)
							(end -0.381 -0.3683)
						)
						(arc
							(start -0.381 0.3683)
							(mid -0.321484 0.511984)
							(end -0.1778 0.5715)
						)
						(arc
							(start 0.1778 0.5715)
							(mid 0.321484 0.511984)
							(end 0.381 0.3683)
						)
						(arc
							(start 0.381 -0.3683)
							(mid 0.321484 -0.511984)
							(end 0.1778 -0.5715)
						)
					)
					(width 0)
					(fill yes)
				)
			)
		)
		(pad "G" smd custom
			(at 0.98425 0.9525 180)
			(size 0.1905 0.1905)
			(layers "B.Cu" "B.Mask" "B.Paste")
			(net "DRIVE_A_25_31_ACT")
			(options
				(clearance outline)
				(anchor circle)
			)
			(primitives
				(gr_poly
					(pts
						(arc
							(start -0.1778 -0.5715)
							(mid -0.321484 -0.511984)
							(end -0.381 -0.3683)
						)
						(arc
							(start -0.381 0.3683)
							(mid -0.321484 0.511984)
							(end -0.1778 0.5715)
						)
						(arc
							(start 0.1778 0.5715)
							(mid 0.321484 0.511984)
							(end 0.381 0.3683)
						)
						(arc
							(start 0.381 -0.3683)
							(mid 0.321484 -0.511984)
							(end 0.1778 -0.5715)
						)
					)
					(width 0)
					(fill yes)
				)
			)
		)
		(pad "S" smd custom
			(at -0.98425 0.9525 180)
			(size 0.1905 0.1905)
			(layers "B.Cu" "B.Mask" "B.Paste")
			(net "GND")
			(options
				(clearance outline)
				(anchor circle)
			)
			(primitives
				(gr_poly
					(pts
						(arc
							(start -0.1778 -0.5715)
							(mid -0.321484 -0.511984)
							(end -0.381 -0.3683)
						)
						(arc
							(start -0.381 0.3683)
							(mid -0.321484 0.511984)
							(end -0.1778 0.5715)
						)
						(arc
							(start 0.1778 0.5715)
							(mid 0.321484 0.511984)
							(end 0.381 0.3683)
						)
						(arc
							(start 0.381 -0.3683)
							(mid 0.321484 -0.511984)
							(end 0.1778 -0.5715)
						)
					)
					(width 0)
					(fill yes)
				)
			)
		)
	)
	(footprint ""
		(layer "B.Cu")
		(at 22.3012 -5.4102)
		(property "Reference" "Q2"
			(at 0 0 0)
			(layer "B.SilkS")
			(hide yes)
			(effects
				(font
					(size 1.27 1.27)
				)
				(justify mirror)
			)
		)
		(property "Value" "SSM3K324R-GP"
			(at -0.127 -8.9662 0)
			(unlocked yes)
			(layer "B.Fab")
			(hide yes)
			(effects
				(font
					(size 1.016 1.016)
					(thickness 0.1524)
				)
				(justify mirror)
			)
		)
		(property "Device Type" "SOT23DGS2D4H35"
			(at -0.127 -10.4902 0)
			(unlocked yes)
			(layer "B.Fab")
			(hide yes)
			(effects
				(font
					(size 1.016 1.016)
					(thickness 0.1524)
				)
				(justify mirror)
			)
		)
		(duplicate_pad_numbers_are_jumpers no)
		(fp_line
			(start -1.651 -1.778)
			(end 1.651 -1.778)
			(stroke
				(width 0.1524)
				(type default)
			)
			(layer "B.SilkS")
		)
		(fp_line
			(start -1.651 1.778)
			(end -1.651 -1.778)
			(stroke
				(width 0.1524)
				(type default)
			)
			(layer "B.SilkS")
		)
		(fp_line
			(start 1.651 -1.778)
			(end 1.651 1.778)
			(stroke
				(width 0.1524)
				(type default)
			)
			(layer "B.SilkS")
		)
		(fp_line
			(start 1.651 1.778)
			(end -1.651 1.778)
			(stroke
				(width 0.1524)
				(type default)
			)
			(layer "B.SilkS")
		)
		(fp_poly
			(pts
				(xy 1.778 1.8796) (xy 1.778 -1.8796) (xy -1.778 -1.8796) (xy -1.778 1.8796)
			)
			(stroke
				(width 0)
				(type default)
			)
			(fill no)
			(layer "B.CrtYd")
		)
		(fp_poly
			(pts
				(xy 1.778 1.8796) (xy 1.778 -1.8796) (xy -1.778 -1.8796) (xy -1.778 1.8796)
			)
			(stroke
				(width 0)
				(type default)
			)
			(fill no)
			(layer "B.Fab")
		)
		(pad "D" smd custom
			(at 0 -0.9525 180)
			(size 0.1905 0.1905)
			(layers "B.Cu" "B.Mask" "B.Paste")
			(net "DRV_ACT_24_30_N")
			(options
				(clearance outline)
				(anchor circle)
			)
			(primitives
				(gr_poly
					(pts
						(arc
							(start -0.1778 -0.5715)
							(mid -0.321484 -0.511984)
							(end -0.381 -0.3683)
						)
						(arc
							(start -0.381 0.3683)
							(mid -0.321484 0.511984)
							(end -0.1778 0.5715)
						)
						(arc
							(start 0.1778 0.5715)
							(mid 0.321484 0.511984)
							(end 0.381 0.3683)
						)
						(arc
							(start 0.381 -0.3683)
							(mid 0.321484 -0.511984)
							(end 0.1778 -0.5715)
						)
					)
					(width 0)
					(fill yes)
				)
			)
		)
		(pad "G" smd custom
			(at 0.98425 0.9525 180)
			(size 0.1905 0.1905)
			(layers "B.Cu" "B.Mask" "B.Paste")
			(net "DRIVE_A_24_30_ACT")
			(options
				(clearance outline)
				(anchor circle)
			)
			(primitives
				(gr_poly
					(pts
						(arc
							(start -0.1778 -0.5715)
							(mid -0.321484 -0.511984)
							(end -0.381 -0.3683)
						)
						(arc
							(start -0.381 0.3683)
							(mid -0.321484 0.511984)
							(end -0.1778 0.5715)
						)
						(arc
							(start 0.1778 0.5715)
							(mid 0.321484 0.511984)
							(end 0.381 0.3683)
						)
						(arc
							(start 0.381 -0.3683)
							(mid 0.321484 -0.511984)
							(end 0.1778 -0.5715)
						)
					)
					(width 0)
					(fill yes)
				)
			)
		)
		(pad "S" smd custom
			(at -0.98425 0.9525 180)
			(size 0.1905 0.1905)
			(layers "B.Cu" "B.Mask" "B.Paste")
			(net "GND")
			(options
				(clearance outline)
				(anchor circle)
			)
			(primitives
				(gr_poly
					(pts
						(arc
							(start -0.1778 -0.5715)
							(mid -0.321484 -0.511984)
							(end -0.381 -0.3683)
						)
						(arc
							(start -0.381 0.3683)
							(mid -0.321484 0.511984)
							(end -0.1778 0.5715)
						)
						(arc
							(start 0.1778 0.5715)
							(mid 0.321484 0.511984)
							(end 0.381 0.3683)
						)
						(arc
							(start 0.381 -0.3683)
							(mid 0.321484 -0.511984)
							(end 0.1778 -0.5715)
						)
					)
					(width 0)
					(fill yes)
				)
			)
		)
	)
	(footprint ""
		(layer "B.Cu")
		(at 112.395 -6.0198 180)
		(property "Reference" "R8"
			(at 0 0 0)
			(layer "B.SilkS")
			(hide yes)
			(effects
				(font
					(size 1.27 1.27)
				)
				(justify mirror)
			)
		)
		(property "Value" "91R3F-1-GP"
			(at 0.0254 -2.5146 180)
			(unlocked yes)
			(layer "B.Fab")
			(hide yes)
			(effects
				(font
					(size 1.016 1.016)
					(thickness 0.1524)
				)
				(justify mirror)
			)
		)
		(property "Device Type" "R603H22"
			(at 0.0254 -4.0386 180)
			(unlocked yes)
			(layer "B.Fab")
			(hide yes)
			(effects
				(font
					(size 1.016 1.016)
					(thickness 0.1524)
				)
				(justify mirror)
			)
		)
		(duplicate_pad_numbers_are_jumpers no)
		(fp_line
			(start 0.4826 0)
			(end 0.2032 0)
			(stroke
				(width 0.2032)
				(type default)
			)
			(layer "B.SilkS")
		)
		(fp_line
			(start -0.2032 0)
			(end -0.4826 0)
			(stroke
				(width 0.2032)
				(type default)
			)
			(layer "B.SilkS")
		)
		(fp_rect
			(start 0.5842 1.3335)
			(end -0.5842 -1.3335)
			(stroke
				(width 0)
				(type default)
			)
			(fill no)
			(layer "B.CrtYd")
		)
		(fp_rect
			(start 0.5842 1.3335)
			(end -0.5842 -1.3335)
			(stroke
				(width 0)
				(type default)
			)
			(fill no)
			(layer "B.Fab")
		)
		(pad "1" smd custom
			(at 0 -0.762)
			(size 0.2159 0.2159)
			(layers "B.Cu" "B.Mask" "B.Paste")
			(net "P5V_A")
			(options
				(clearance outline)
				(anchor circle)
			)
			(primitives
				(gr_poly
					(pts
						(arc
							(start -0.3302 0.4318)
							(mid -0.402042 0.402042)
							(end -0.4318 0.3302)
						)
						(arc
							(start -0.4318 -0.3302)
							(mid -0.402042 -0.402042)
							(end -0.3302 -0.4318)
						)
						(arc
							(start 0.3302 -0.4318)
							(mid 0.402042 -0.402042)
							(end 0.4318 -0.3302)
						)
						(arc
							(start 0.4318 0.3302)
							(mid 0.402042 0.402042)
							(end 0.3302 0.4318)
						)
					)
					(width 0)
					(fill yes)
				)
			)
		)
		(pad "2" smd custom
			(at 0 0.762)
			(size 0.2159 0.2159)
			(layers "B.Cu" "B.Mask" "B.Paste")
			(net "DRV_ACT_27_33")
			(options
				(clearance outline)
				(anchor circle)
			)
			(primitives
				(gr_poly
					(pts
						(arc
							(start -0.3302 0.4318)
							(mid -0.402042 0.402042)
							(end -0.4318 0.3302)
						)
						(arc
							(start -0.4318 -0.3302)
							(mid -0.402042 -0.402042)
							(end -0.3302 -0.4318)
						)
						(arc
							(start 0.3302 -0.4318)
							(mid 0.402042 -0.402042)
							(end 0.4318 -0.3302)
						)
						(arc
							(start 0.4318 0.3302)
							(mid 0.402042 0.402042)
							(end 0.3302 0.4318)
						)
					)
					(width 0)
					(fill yes)
				)
			)
		)
	)
	(footprint ""
		(layer "B.Cu")
		(at 167.9194 -5.7658 180)
		(property "Reference" "R12"
			(at 0 0 0)
			(layer "B.SilkS")
			(hide yes)
			(effects
				(font
					(size 1.27 1.27)
				)
				(justify mirror)
			)
		)
		(property "Value" "91R3F-1-GP"
			(at 0.0254 -2.5146 180)
			(unlocked yes)
			(layer "B.Fab")
			(hide yes)
			(effects
				(font
					(size 1.016 1.016)
					(thickness 0.1524)
				)
				(justify mirror)
			)
		)
		(property "Device Type" "R603H22"
			(at 0.0254 -4.0386 180)
			(unlocked yes)
			(layer "B.Fab")
			(hide yes)
			(effects
				(font
					(size 1.016 1.016)
					(thickness 0.1524)
				)
				(justify mirror)
			)
		)
		(duplicate_pad_numbers_are_jumpers no)
		(fp_line
			(start 0.4826 0)
			(end 0.2032 0)
			(stroke
				(width 0.2032)
				(type default)
			)
			(layer "B.SilkS")
		)
		(fp_line
			(start -0.2032 0)
			(end -0.4826 0)
			(stroke
				(width 0.2032)
				(type default)
			)
			(layer "B.SilkS")
		)
		(fp_rect
			(start 0.5842 1.3335)
			(end -0.5842 -1.3335)
			(stroke
				(width 0)
				(type default)
			)
			(fill no)
			(layer "B.CrtYd")
		)
		(fp_rect
			(start 0.5842 1.3335)
			(end -0.5842 -1.3335)
			(stroke
				(width 0)
				(type default)
			)
			(fill no)
			(layer "B.Fab")
		)
		(pad "1" smd custom
			(at 0 -0.762)
			(size 0.2159 0.2159)
			(layers "B.Cu" "B.Mask" "B.Paste")
			(net "P5V_A")
			(options
				(clearance outline)
				(anchor circle)
			)
			(primitives
				(gr_poly
					(pts
						(arc
							(start -0.3302 0.4318)
							(mid -0.402042 0.402042)
							(end -0.4318 0.3302)
						)
						(arc
							(start -0.4318 -0.3302)
							(mid -0.402042 -0.402042)
							(end -0.3302 -0.4318)
						)
						(arc
							(start 0.3302 -0.4318)
							(mid 0.402042 -0.402042)
							(end 0.4318 -0.3302)
						)
						(arc
							(start 0.4318 0.3302)
							(mid 0.402042 0.402042)
							(end 0.3302 0.4318)
						)
					)
					(width 0)
					(fill yes)
				)
			)
		)
		(pad "2" smd custom
			(at 0 0.762)
			(size 0.2159 0.2159)
			(layers "B.Cu" "B.Mask" "B.Paste")
			(net "DRV_ACT_29_35")
			(options
				(clearance outline)
				(anchor circle)
			)
			(primitives
				(gr_poly
					(pts
						(arc
							(start -0.3302 0.4318)
							(mid -0.402042 0.402042)
							(end -0.4318 0.3302)
						)
						(arc
							(start -0.4318 -0.3302)
							(mid -0.402042 -0.402042)
							(end -0.3302 -0.4318)
						)
						(arc
							(start 0.3302 -0.4318)
							(mid 0.402042 -0.402042)
							(end 0.4318 -0.3302)
						)
						(arc
							(start 0.4318 0.3302)
							(mid 0.402042 0.402042)
							(end 0.3302 0.4318)
						)
					)
					(width 0)
					(fill yes)
				)
			)
		)
	)
	(footprint ""
		(layer "B.Cu")
		(at 32.893 -2.6416 -90)
		(property "Reference" "R16"
			(at 0 0 90)
			(layer "B.SilkS")
			(hide yes)
			(effects
				(font
					(size 1.27 1.27)
				)
				(justify mirror)
			)
		)
		(property "Value" "4K7R2F-GP"
			(at -0.064008 -3.993896 270)
			(unlocked yes)
			(layer "B.Fab")
			(hide yes)
			(effects
				(font
					(size 1.016 1.016)
					(thickness 0.1524)
				)
				(justify mirror)
			)
		)
		(property "Device Type" "R402H16"
			(at -0.064008 -5.517896 270)
			(unlocked yes)
			(layer "B.Fab")
			(hide yes)
			(effects
				(font
					(size 1.016 1.016)
					(thickness 0.1524)
				)
				(justify mirror)
			)
		)
		(duplicate_pad_numbers_are_jumpers no)
		(fp_line
			(start -0.508 -0.9398)
			(end 0.508 -0.9398)
			(stroke
				(width 0.1524)
				(type default)
			)
			(layer "B.SilkS")
		)
		(fp_line
			(start 0.508 -0.9398)
			(end 0.508 0.9398)
			(stroke
				(width 0.1524)
				(type default)
			)
			(layer "B.SilkS")
		)
		(fp_rect
			(start 0.508 0.9398)
			(end -0.508 -0.9398)
			(stroke
				(width 0)
				(type default)
			)
			(fill no)
			(layer "B.CrtYd")
		)
		(fp_rect
			(start 0.508 0.9398)
			(end -0.508 -0.9398)
			(stroke
				(width 0)
				(type default)
			)
			(fill no)
			(layer "B.Fab")
		)
		(pad "1" smd custom
			(at 0 -0.4445 90)
			(size 0.1397 0.1397)
			(layers "B.Cu" "B.Mask" "B.Paste")
			(net "DRIVE_A_25_31_ACT")
			(options
				(clearance outline)
				(anchor circle)
			)
			(primitives
				(gr_poly
					(pts
						(arc
							(start -0.1778 0.2794)
							(mid -0.249642 0.249642)
							(end -0.2794 0.1778)
						)
						(arc
							(start -0.2794 -0.1778)
							(mid -0.249642 -0.249642)
							(end -0.1778 -0.2794)
						)
						(arc
							(start 0.1778 -0.2794)
							(mid 0.249642 -0.249642)
							(end 0.2794 -0.1778)
						)
						(arc
							(start 0.2794 0.1778)
							(mid 0.249642 0.249642)
							(end 0.1778 0.2794)
						)
					)
					(width 0)
					(fill yes)
				)
			)
		)
		(pad "2" smd custom
			(at 0 0.4445 90)
			(size 0.1397 0.1397)
			(layers "B.Cu" "B.Mask" "B.Paste")
			(net "GND")
			(options
				(clearance outline)
				(anchor circle)
			)
			(primitives
				(gr_poly
					(pts
						(arc
							(start -0.1778 0.2794)
							(mid -0.249642 0.249642)
							(end -0.2794 0.1778)
						)
						(arc
							(start -0.2794 -0.1778)
							(mid -0.249642 -0.249642)
							(end -0.1778 -0.2794)
						)
						(arc
							(start 0.1778 -0.2794)
							(mid 0.249642 -0.249642)
							(end 0.2794 -0.1778)
						)
						(arc
							(start 0.2794 0.1778)
							(mid 0.249642 0.249642)
							(end 0.1778 0.2794)
						)
					)
					(width 0)
					(fill yes)
				)
			)
		)
	)
	(footprint ""
		(layer "B.Cu")
		(at 138.4554 -5.715)
		(property "Reference" "Q9"
			(at 0 0 0)
			(layer "B.SilkS")
			(hide yes)
			(effects
				(font
					(size 1.27 1.27)
				)
				(justify mirror)
			)
		)
		(property "Value" "2N7002K-2-GP"
			(at -0.127 -8.9662 0)
			(unlocked yes)
			(layer "B.Fab")
			(hide yes)
			(effects
				(font
					(size 1.016 1.016)
					(thickness 0.1524)
				)
				(justify mirror)
			)
		)
		(property "Device Type" "SOT23DGS2D4H44"
			(at -0.127 -10.4902 0)
			(unlocked yes)
			(layer "B.Fab")
			(hide yes)
			(effects
				(font
					(size 1.016 1.016)
					(thickness 0.1524)
				)
				(justify mirror)
			)
		)
		(duplicate_pad_numbers_are_jumpers no)
		(fp_line
			(start -1.651 -1.778)
			(end 1.651 -1.778)
			(stroke
				(width 0.1524)
				(type default)
			)
			(layer "B.SilkS")
		)
		(fp_line
			(start -1.651 1.778)
			(end -1.651 -1.778)
			(stroke
				(width 0.1524)
				(type default)
			)
			(layer "B.SilkS")
		)
		(fp_line
			(start 1.651 -1.778)
			(end 1.651 1.778)
			(stroke
				(width 0.1524)
				(type default)
			)
			(layer "B.SilkS")
		)
		(fp_line
			(start 1.651 1.778)
			(end -1.651 1.778)
			(stroke
				(width 0.1524)
				(type default)
			)
			(layer "B.SilkS")
		)
		(fp_poly
			(pts
				(xy 1.778 1.8796) (xy 1.778 -1.8796) (xy -1.778 -1.8796) (xy -1.778 1.8796)
			)
			(stroke
				(width 0)
				(type default)
			)
			(fill no)
			(layer "B.CrtYd")
		)
		(fp_poly
			(pts
				(xy 1.778 1.8796) (xy 1.778 -1.8796) (xy -1.778 -1.8796) (xy -1.778 1.8796)
			)
			(stroke
				(width 0)
				(type default)
			)
			(fill no)
			(layer "B.Fab")
		)
		(pad "D" smd custom
			(at 0 -0.9525 180)
			(size 0.1905 0.1905)
			(layers "B.Cu" "B.Mask" "B.Paste")
			(net "FLT_HDD28_34_N")
			(options
				(clearance outline)
				(anchor circle)
			)
			(primitives
				(gr_poly
					(pts
						(arc
							(start -0.1778 -0.5715)
							(mid -0.321484 -0.511984)
							(end -0.381 -0.3683)
						)
						(arc
							(start -0.381 0.3683)
							(mid -0.321484 0.511984)
							(end -0.1778 0.5715)
						)
						(arc
							(start 0.1778 0.5715)
							(mid 0.321484 0.511984)
							(end 0.381 0.3683)
						)
						(arc
							(start 0.381 -0.3683)
							(mid 0.321484 -0.511984)
							(end 0.1778 -0.5715)
						)
					)
					(width 0)
					(fill yes)
				)
			)
		)
		(pad "G" smd custom
			(at 0.98425 0.9525 180)
			(size 0.1905 0.1905)
			(layers "B.Cu" "B.Mask" "B.Paste")
			(net "DRIVE_A_28_34_FLT_LED")
			(options
				(clearance outline)
				(anchor circle)
			)
			(primitives
				(gr_poly
					(pts
						(arc
							(start -0.1778 -0.5715)
							(mid -0.321484 -0.511984)
							(end -0.381 -0.3683)
						)
						(arc
							(start -0.381 0.3683)
							(mid -0.321484 0.511984)
							(end -0.1778 0.5715)
						)
						(arc
							(start 0.1778 0.5715)
							(mid 0.321484 0.511984)
							(end 0.381 0.3683)
						)
						(arc
							(start 0.381 -0.3683)
							(mid 0.321484 -0.511984)
							(end 0.1778 -0.5715)
						)
					)
					(width 0)
					(fill yes)
				)
			)
		)
		(pad "S" smd custom
			(at -0.98425 0.9525 180)
			(size 0.1905 0.1905)
			(layers "B.Cu" "B.Mask" "B.Paste")
			(net "GND")
			(options
				(clearance outline)
				(anchor circle)
			)
			(primitives
				(gr_poly
					(pts
						(arc
							(start -0.1778 -0.5715)
							(mid -0.321484 -0.511984)
							(end -0.381 -0.3683)
						)
						(arc
							(start -0.381 0.3683)
							(mid -0.321484 0.511984)
							(end -0.1778 0.5715)
						)
						(arc
							(start 0.1778 0.5715)
							(mid 0.321484 0.511984)
							(end 0.381 0.3683)
						)
						(arc
							(start 0.381 -0.3683)
							(mid 0.321484 -0.511984)
							(end 0.1778 -0.5715)
						)
					)
					(width 0)
					(fill yes)
				)
			)
		)
	)
)
